# S9S_MB_2U (Grand Teton) — schematic netlist excerpt (pin names and nets, part order shuffled) for the footprints in the layout excerpt that follows; sources: Cadence DE-HDL packaged netlist, KiCad conversion of 03242023_DA0F0TMBIJ0_F0T_Motherboard_J_brd_V01_OCP.brd

J32  SCONN288_ADR50017P087CC  SCONN288_ADR50017-P087CC IO  pkg DDR288S_1-1VXB  page 113
  VIN_BULK0  = P12V_S3_AUX_CPU1_NVDIMM
  RFU0  = TP_CHH_CPU1_DIMM2_FRU_0
  VIN_MGMT  = P3V3_AUX
  HSCL  = I3C_SPD_DDREFGH_CPU1_LVC1_SCL_7
  HSDA  = I3C_SPD_DDREFGH_CPU1_LVC1_SDA
  VSS0  = GND
  DQ0_A  = M_H_CPU1_SA_DQ<0>
  VSS1  = GND
  DQ1_A  = M_H_CPU1_SA_DQ<1>
  VSS2  = GND
  DQS0_A_T  = M_H_CPU1_SA_DQS_DP<0>
  DQS0_A_C  = M_H_CPU1_SA_DQS_DN<0>
  VSS3  = GND
  DQ4_A  = M_H_CPU1_SA_DQ<4>
  VSS4  = GND
  DQ5_A  = M_H_CPU1_SA_DQ<5>
  VSS5  = GND
  DQ8_A  = M_H_CPU1_SA_DQ<8>
  VSS6  = GND
  DQ9_A  = M_H_CPU1_SA_DQ<9>
  VSS7  = GND
  DQS1_A_T  = M_H_CPU1_SA_DQS_DP<1>
  DQS1_A_C  = M_H_CPU1_SA_DQS_DN<1>
  VSS8  = GND
  DQ12_A  = M_H_CPU1_SA_DQ<12>
  VSS9  = GND
  DQ13_A  = M_H_CPU1_SA_DQ<13>
  VSS10  = GND
  DQ16_A  = M_H_CPU1_SA_DQ<16>
  VSS11  = GND
  DQ17_A  = M_H_CPU1_SA_DQ<17>
  VSS12  = GND
  DQS2_A_T  = M_H_CPU1_SA_DQS_DP<2>
  DQS2_A_C  = M_H_CPU1_SA_DQS_DN<2>
  VSS13  = GND
  DQ20_A  = M_H_CPU1_SA_DQ<20>
  VSS14  = GND
  DQ21_A  = M_H_CPU1_SA_DQ<21>
  VSS15  = GND
  DQ24_A  = M_H_CPU1_SA_DQ<24>
  VSS16  = GND
  DQ25_A  = M_H_CPU1_SA_DQ<25>
  VSS17  = GND
  DQS3_A_T  = M_H_CPU1_SA_DQS_DP<3>
  DQS3_A_C  = M_H_CPU1_SA_DQS_DN<3>
  VSS18  = GND
  DQ28_A  = M_H_CPU1_SA_DQ<28>
  VSS19  = GND
  DQ29_A  = M_H_CPU1_SA_DQ<29>
  VSS20  = GND
  CB0_A  = M_H_CPU1_SA_CB<0>
  VSS21  = GND
  CB1_A  = M_H_CPU1_SA_CB<1>
  VSS22  = GND
  DQS4_A_T  = M_H_CPU1_SA_DQS_DP<4>
  DQS4_A_C  = M_H_CPU1_SA_DQS_DN<4>
  VSS23  = GND
  CB4_A  = M_H_CPU1_SA_CB<4>
  VSS24  = GND
  CB5_A  = M_H_CPU1_SA_CB<5>
  VSS25  = GND
  ALERT_N  = M_H_CPU1_ALERT_N
  VSS26  = GND
  CS0_A_N  = M_H_CPU1_SA_CS_N<2>
  VSS27  = GND
  CA0_A  = M_H_CPU1_SA_CA<0>
  VSS28  = GND
  CA2_A  = M_H_CPU1_SA_CA<2>
  VSS29  = GND
  CA4_A  = M_H_CPU1_SA_CA<4>
  VSS30  = GND
  CA6_A  = M_H_CPU1_SA_CA<6>
  VSS31  = GND
  PAR_A  = M_H_CPU1_SA_PAR
  VSS32  = GND
  CA0_B  = M_H_CPU1_SB_CA<0>
  VSS33  = GND
  CA2_B  = M_H_CPU1_SB_CA<2>
  VSS34  = GND
  CA4_B  = M_H_CPU1_SB_CA<4>
  VSS35  = GND
  CA6_B  = M_H_CPU1_SB_CA<6>
  VSS36  = GND
  CS0_B_N  = M_H_CPU1_SB_CS_N<2>
  VSS37  = GND
  \lbd||rsp_a_n\  = M_H_CPU1_SA_RSP<1>
  \lbs||rsp_b_n\  = M_H_CPU1_SB_RSP<1>
  VSS38  = GND
  CB4_B  = M_H_CPU1_SB_CB<4>
  VSS39  = GND
  CB5_B  = M_H_CPU1_SB_CB<5>
  VSS40  = GND
  \dqs9_b_t||tdqs9_b_t||dbi4_b_n\  = M_H_CPU1_SB_DQS_DP<9>
  \dqs9_b_c||tdqs9_b_c\  = M_H_CPU1_SB_DQS_DN<9>
  VSS41  = GND
  CB0_B  = M_H_CPU1_SB_CB<0>
  VSS42  = GND
  CB1_B  = M_H_CPU1_SB_CB<1>
  VSS43  = GND
  DQ0_B  = M_H_CPU1_SB_DQ<0>
  VSS44  = GND
  DQ1_B  = M_H_CPU1_SB_DQ<1>
  VSS45  = GND
  DQS0_B_T  = M_H_CPU1_SB_DQS_DP<0>
  DQS0_B_C  = M_H_CPU1_SB_DQS_DN<0>
  VSS46  = GND
  DQ4_B  = M_H_CPU1_SB_DQ<4>
  VSS47  = GND
  DQ5_B  = M_H_CPU1_SB_DQ<5>
  VSS48  = GND
  DQ8_B  = M_H_CPU1_SB_DQ<8>
  VSS49  = GND
  DQ9_B  = M_H_CPU1_SB_DQ<9>
  VSS50  = GND
  DQS1_B_T  = M_H_CPU1_SB_DQS_DP<1>
  DQS1_B_C  = M_H_CPU1_SB_DQS_DN<1>
  VSS51  = GND
  DQ12_B  = M_H_CPU1_SB_DQ<12>
  VSS52  = GND
  DQ13_B  = M_H_CPU1_SB_DQ<13>
  VSS53  = GND
  DQ16_B  = M_H_CPU1_SB_DQ<16>
  VSS54  = GND
  DQ17_B  = M_H_CPU1_SB_DQ<17>
  VSS55  = GND
  DQS2_B_T  = M_H_CPU1_SB_DQS_DP<2>
  DQS2_B_C  = M_H_CPU1_SB_DQS_DN<2>
  VSS56  = GND
  DQ20_B  = M_H_CPU1_SB_DQ<20>
  VSS57  = GND
  DQ21_B  = M_H_CPU1_SB_DQ<21>
  VSS58  = GND
  DQ24_B  = M_H_CPU1_SB_DQ<24>
  VSS59  = GND
  DQ25_B  = M_H_CPU1_SB_DQ<25>
  VSS60  = GND
  DQS3_B_T  = M_H_CPU1_SB_DQS_DP<3>
  DQS3_B_C  = M_H_CPU1_SB_DQS_DN<3>
  VSS61  = GND
  DQ28_B  = M_H_CPU1_SB_DQ<28>
  VSS62  = GND
  DQ29_B  = M_H_CPU1_SB_DQ<29>
  VSS63  = GND
  RFU1  = TP_CHH_CPU1_DIMM2_FRU_1
  VIN_BULK1  = P12V_S3_AUX_CPU1_NVDIMM
  VIN_BULK2  = P12V_S3_AUX_CPU1_NVDIMM
  \pwr_good||fail_n\  = PWRGD_CHH_CPU1_DIMM2
  HSA  = PD_CHH_CPU1_DIMM2_SAA
  RFU2  = TP_CHH_CPU1_DIMM2_FRU_2
  RFU3  = TP_CHH_CPU1_DIMM2_FRU_3
  VSS64  = GND
  DQ2_A  = M_H_CPU1_SA_DQ<2>
  VSS65  = GND
  DQ3_A  = M_H_CPU1_SA_DQ<3>
  VSS66  = GND
  \dqs5_a_c||tdqs5_a_c||dqs5_a_t||tdqs5_a_t\  = M_H_CPU1_SA_DQS_DN<5>
  \dqs5_a_t||tdqs5_a_t\  = M_H_CPU1_SA_DQS_DP<5>
  VSS67  = GND
  DQ6_A  = M_H_CPU1_SA_DQ<6>
  VSS68  = GND
  DQ7_A  = M_H_CPU1_SA_DQ<7>
  VSS69  = GND
  DQ10_A  = M_H_CPU1_SA_DQ<10>
  VSS70  = GND
  DQ11_A  = M_H_CPU1_SA_DQ<11>
  VSS71  = GND
  \dqs6_a_c||tdqs6_a_c||dqs6_a_t||tdqs6_a_t\  = M_H_CPU1_SA_DQS_DN<6>
  \dqs6_a_t||tdqs6_a_t\  = M_H_CPU1_SA_DQS_DP<6>
  VSS72  = GND
  DQ14_A  = M_H_CPU1_SA_DQ<14>
  VSS73  = GND
  DQ15_A  = M_H_CPU1_SA_DQ<15>
  VSS74  = GND
  DQ18_A  = M_H_CPU1_SA_DQ<18>
  VSS75  = GND
  DQ19_A  = M_H_CPU1_SA_DQ<19>
  VSS76  = GND
  \dqs7_a_c||tdqs7_a_c\  = M_H_CPU1_SA_DQS_DN<7>
  \dqs7_a_t||tdqs7_a_t\  = M_H_CPU1_SA_DQS_DP<7>
  VSS77  = GND
  DQ22_A  = M_H_CPU1_SA_DQ<22>
  VSS78  = GND
  DQ23_A  = M_H_CPU1_SA_DQ<23>
  VSS79  = GND
  DQ26_A  = M_H_CPU1_SA_DQ<26>
  VSS80  = GND
  DQ27_A  = M_H_CPU1_SA_DQ<27>
  VSS81  = GND
  \dqs8_a_c||tdqs8_a_c\  = M_H_CPU1_SA_DQS_DN<8>
  \dqs8_a_t||tdqs8_a_t\  = M_H_CPU1_SA_DQS_DP<8>
  VSS82  = GND
  DQ30_A  = M_H_CPU1_SA_DQ<30>
  VSS83  = GND
  DQ31_A  = M_H_CPU1_SA_DQ<31>
  VSS84  = GND
  CB2_A  = M_H_CPU1_SA_CB<2>
  VSS85  = GND
  CB3_A  = M_H_CPU1_SA_CB<3>
  VSS86  = GND
  \dqs9_a_c||tdqs9_a_c\  = M_H_CPU1_SA_DQS_DN<9>
  \dqs9_a_t||tdqs9_a_t\  = M_H_CPU1_SA_DQS_DP<9>
  VSS87  = GND
  CB6_A  = M_H_CPU1_SA_CB<6>
  VSS88  = GND
  CB7_A  = M_H_CPU1_SA_CB<7>
  VSS89  = GND
  RESET_N  = RST_M_GH_CPU1_FPGA_N
  VSS90  = GND
  CS1_A_N  = M_H_CPU1_SA_CS_N<3>
  VSS91  = GND
  CA1_A  = M_H_CPU1_SA_CA<1>
  VSS92  = GND
  CA3_A  = M_H_CPU1_SA_CA<3>
  VSS93  = GND
  CA5_A  = M_H_CPU1_SA_CA<5>
  VSS94  = GND
  CK_T  = M_H_CPU1_CLK_DP<1>
  CK_C  = M_H_CPU1_CLK_DN<1>
  VSS95  = GND
  RFU4  = TP_CHH_CPU1_DIMM2_FRU_4
  CA1_B  = M_H_CPU1_SB_CA<1>
  VSS96  = GND
  CA3_B  = M_H_CPU1_SB_CA<3>
  VSS97  = GND
  CA5_B  = M_H_CPU1_SB_CA<5>
  VSS98  = GND
  PAR_B  = M_H_CPU1_SB_PAR
  VSS99  = GND
  CS1_B_N  = M_H_CPU1_SB_CS_N<3>
  VSS100  = GND
  RFU5  = TP_CHH_CPU1_DIMM2_FRU_5
  RFU6  = TP_CHH_CPU1_DIMM2_FRU_6
  VSS101  = GND
  CB6_B  = M_H_CPU1_SB_CB<6>
  VSS102  = GND
  CB7_B  = M_H_CPU1_SB_CB<7>
  VSS103  = GND
  DQS4_B_C  = M_H_CPU1_SB_DQS_DN<4>
  DQS4_B_T  = M_H_CPU1_SB_DQS_DP<4>
  VSS104  = GND
  CB2_B  = M_H_CPU1_SB_CB<2>
  VSS105  = GND
  CB3_B  = M_H_CPU1_SB_CB<3>
  VSS106  = GND
  DQ2_B  = M_H_CPU1_SB_DQ<2>
  VSS107  = GND
  DQ3_B  = M_H_CPU1_SB_DQ<3>
  VSS108  = GND
  \dqs5_b_c||tdqs5_b_c\  = M_H_CPU1_SB_DQS_DN<5>
  \dqs5_b_t||tdqs5_b_t\  = M_H_CPU1_SB_DQS_DP<5>
  VSS109  = GND
  DQ6_B  = M_H_CPU1_SB_DQ<6>
  VSS110  = GND
  DQ7_B  = M_H_CPU1_SB_DQ<7>
  VSS111  = GND
  DQ10_B  = M_H_CPU1_SB_DQ<10>
  VSS112  = GND
  DQ11_B  = M_H_CPU1_SB_DQ<11>
  VSS113  = GND
  \dqs6_b_c||tdqs6_b_c\  = M_H_CPU1_SB_DQS_DN<6>
  \dqs6_b_t||tdqs6_b_t\  = M_H_CPU1_SB_DQS_DP<6>
  VSS114  = GND
  DQ14_B  = M_H_CPU1_SB_DQ<14>
  VSS115  = GND
  DQ15_B  = M_H_CPU1_SB_DQ<15>
  VSS116  = GND
  DQ18_B  = M_H_CPU1_SB_DQ<18>
  VSS117  = GND
  DQ19_B  = M_H_CPU1_SB_DQ<19>
  VSS118  = GND
  \dqs7_b_c||tdqs7_b_c\  = M_H_CPU1_SB_DQS_DN<7>
  \dqs7_b_t||tdqs7_b_t\  = M_H_CPU1_SB_DQS_DP<7>
  VSS119  = GND
  DQ22_B  = M_H_CPU1_SB_DQ<22>
  VSS120  = GND
  DQ23_B  = M_H_CPU1_SB_DQ<23>
  VSS121  = GND
  DQ26_B  = M_H_CPU1_SB_DQ<26>
  VSS122  = GND
  DQ27_B  = M_H_CPU1_SB_DQ<27>
  VSS123  = GND
  \dqs8_b_c||tdqs8_b_c\  = M_H_CPU1_SB_DQS_DN<8>
  \dqs8_b_t||tdqs8_b_t\  = M_H_CPU1_SB_DQS_DP<8>
  VSS124  = GND
  DQ30_B  = M_H_CPU1_SB_DQ<30>
  VSS125  = GND
  DQ31_B  = M_H_CPU1_SB_DQ<31>
  VSS126  = GND
  G1  = GND
  G2  = GND
  G3  = GND

(kicad_pcb
	(version 20260206)
	(generator "pcbnew")
	(generator_version "10.0")
	(general
		(thickness 1.6)
		(legacy_teardrops no)
	)
	(paper "A4")
	(title_block
		(title "03242023_DA0F0TMBIJ0_F0T_Motherboard_J_brd_V01_OCP.brd")
		(comment 1 "Grand Teton / footprint 3133 of 6105 (J32), pads 92-137 of 291")
	)
	(layers
		(0 "F.Cu" signal "TOP")
		(4 "In1.Cu" signal "GND")
		(6 "In2.Cu" signal "IN1")
		(8 "In3.Cu" signal "GND1")
		(10 "In4.Cu" signal "IN2")
		(12 "In5.Cu" signal "GND2")
		(14 "In6.Cu" signal "IN3")
		(16 "In7.Cu" signal "GND3")
		(18 "In8.Cu" signal "VCC")
		(20 "In9.Cu" signal "VCC1")
		(22 "In10.Cu" signal "GND4")
		(24 "In11.Cu" signal "IN4")
		(26 "In12.Cu" signal "GND5")
		(28 "In13.Cu" signal "IN5")
		(30 "In14.Cu" signal "GND6")
		(32 "In15.Cu" signal "IN6")
		(34 "In16.Cu" signal "GND7")
		(2 "B.Cu" signal "BOTTOM")
		(9 "F.Adhes" user "F.Adhesive")
		(11 "B.Adhes" user "B.Adhesive")
		(13 "F.Paste" user "Package Geometry/Pastemask Top")
		(15 "B.Paste" user "Package Geometry/Pastemask Bottom")
		(5 "F.SilkS" user "Ref Des/Silkscreen Top")
		(7 "B.SilkS" user "Ref Des/Silkscreen Bottom")
		(1 "F.Mask" user "Board Geometry/Soldermask Top")
		(3 "B.Mask" user "Board Geometry/Soldermask Bottom")
		(17 "Dwgs.User" user "User.Drawings")
		(19 "Cmts.User" user "User.Comments")
		(21 "Eco1.User" user "User.Eco1")
		(23 "Eco2.User" user "User.Eco2")
		(25 "Edge.Cuts" user "Board Geometry/Outline")
		(27 "Margin" user)
		(31 "F.CrtYd" user "Package Geometry/Place Bound Top")
		(29 "B.CrtYd" user "Package Geometry/Place Bound Bottom")
		(35 "F.Fab" user "Ref Des/Assembly Top")
		(33 "B.Fab" user "Ref Des/Assembly Bottom")
	)
	(footprint ""
		(layer "F.Cu")
		(at 206.12608 -258.091686)
		(property "Reference" "J32"
			(at 0.68834 -81.826608 0)
			(unlocked yes)
			(layer "F.SilkS")
			(effects
				(font
					(size 0.7874 0.5842)
					(thickness 0.1524)
				)
				(justify left)
			)
		)
		(property "Value" ""
			(at 0 0 0)
			(layer "F.Fab")
			(effects
				(font
					(size 1.27 1.27)
				)
			)
		)
		(duplicate_pad_numbers_are_jumpers no)
		(pad "92" smd rect
			(at -2.050034 19.12493 270)
			(size 0.519938 1.4986)
			(layers "F.Cu" "F.Mask" "F.Paste")
			(net "GND")
		)
		(pad "93" smd rect
			(at -2.050034 19.975068 270)
			(size 0.519938 1.4986)
			(layers "F.Cu" "F.Mask" "F.Paste")
			(net "M_H_CPU1_SB_DQS_DP<9>")
		)
		(pad "94" smd rect
			(at -2.050034 20.824952 270)
			(size 0.519938 1.4986)
			(layers "F.Cu" "F.Mask" "F.Paste")
			(net "M_H_CPU1_SB_DQS_DN<9>")
		)
		(pad "95" smd rect
			(at -2.050034 21.67509 270)
			(size 0.519938 1.4986)
			(layers "F.Cu" "F.Mask" "F.Paste")
			(net "GND")
		)
		(pad "96" smd rect
			(at -2.050034 22.524974 270)
			(size 0.519938 1.4986)
			(layers "F.Cu" "F.Mask" "F.Paste")
			(net "M_H_CPU1_SB_CB<0>")
		)
		(pad "97" smd rect
			(at -2.050034 23.375112 270)
			(size 0.519938 1.4986)
			(layers "F.Cu" "F.Mask" "F.Paste")
			(net "GND")
		)
		(pad "98" smd rect
			(at -2.050034 24.224996 270)
			(size 0.519938 1.4986)
			(layers "F.Cu" "F.Mask" "F.Paste")
			(net "M_H_CPU1_SB_CB<1>")
		)
		(pad "99" smd rect
			(at -2.050034 25.07488 270)
			(size 0.519938 1.4986)
			(layers "F.Cu" "F.Mask" "F.Paste")
			(net "GND")
		)
		(pad "100" smd rect
			(at -2.050034 25.925018 270)
			(size 0.519938 1.4986)
			(layers "F.Cu" "F.Mask" "F.Paste")
			(net "M_H_CPU1_SB_DQ<0>")
		)
		(pad "101" smd rect
			(at -2.050034 26.774902 270)
			(size 0.519938 1.4986)
			(layers "F.Cu" "F.Mask" "F.Paste")
			(net "GND")
		)
		(pad "102" smd rect
			(at -2.050034 27.62504 270)
			(size 0.519938 1.4986)
			(layers "F.Cu" "F.Mask" "F.Paste")
			(net "M_H_CPU1_SB_DQ<1>")
		)
		(pad "103" smd rect
			(at -2.050034 28.474924 270)
			(size 0.519938 1.4986)
			(layers "F.Cu" "F.Mask" "F.Paste")
			(net "GND")
		)
		(pad "104" smd rect
			(at -2.050034 29.325062 270)
			(size 0.519938 1.4986)
			(layers "F.Cu" "F.Mask" "F.Paste")
			(net "M_H_CPU1_SB_DQS_DP<0>")
		)
		(pad "105" smd rect
			(at -2.050034 30.174946 270)
			(size 0.519938 1.4986)
			(layers "F.Cu" "F.Mask" "F.Paste")
			(net "M_H_CPU1_SB_DQS_DN<0>")
		)
		(pad "106" smd rect
			(at -2.050034 31.025084 270)
			(size 0.519938 1.4986)
			(layers "F.Cu" "F.Mask" "F.Paste")
			(net "GND")
		)
		(pad "107" smd rect
			(at -2.050034 31.874968 270)
			(size 0.519938 1.4986)
			(layers "F.Cu" "F.Mask" "F.Paste")
			(net "M_H_CPU1_SB_DQ<4>")
		)
		(pad "108" smd rect
			(at -2.050034 32.725106 270)
			(size 0.519938 1.4986)
			(layers "F.Cu" "F.Mask" "F.Paste")
			(net "GND")
		)
		(pad "109" smd rect
			(at -2.050034 33.57499 270)
			(size 0.519938 1.4986)
			(layers "F.Cu" "F.Mask" "F.Paste")
			(net "M_H_CPU1_SB_DQ<5>")
		)
		(pad "110" smd rect
			(at -2.050034 34.425128 270)
			(size 0.519938 1.4986)
			(layers "F.Cu" "F.Mask" "F.Paste")
			(net "GND")
		)
		(pad "111" smd rect
			(at -2.050034 35.275012 270)
			(size 0.519938 1.4986)
			(layers "F.Cu" "F.Mask" "F.Paste")
			(net "M_H_CPU1_SB_DQ<8>")
		)
		(pad "112" smd rect
			(at -2.050034 36.124896 270)
			(size 0.519938 1.4986)
			(layers "F.Cu" "F.Mask" "F.Paste")
			(net "GND")
		)
		(pad "113" smd rect
			(at -2.050034 36.975034 270)
			(size 0.519938 1.4986)
			(layers "F.Cu" "F.Mask" "F.Paste")
			(net "M_H_CPU1_SB_DQ<9>")
		)
		(pad "114" smd rect
			(at -2.050034 37.824918 270)
			(size 0.519938 1.4986)
			(layers "F.Cu" "F.Mask" "F.Paste")
			(net "GND")
		)
		(pad "115" smd rect
			(at -2.050034 38.675056 270)
			(size 0.519938 1.4986)
			(layers "F.Cu" "F.Mask" "F.Paste")
			(net "M_H_CPU1_SB_DQS_DP<1>")
		)
		(pad "116" smd rect
			(at -2.050034 39.52494 270)
			(size 0.519938 1.4986)
			(layers "F.Cu" "F.Mask" "F.Paste")
			(net "M_H_CPU1_SB_DQS_DN<1>")
		)
		(pad "117" smd rect
			(at -2.050034 40.375078 270)
			(size 0.519938 1.4986)
			(layers "F.Cu" "F.Mask" "F.Paste")
			(net "GND")
		)
		(pad "118" smd rect
			(at -2.050034 41.224962 270)
			(size 0.519938 1.4986)
			(layers "F.Cu" "F.Mask" "F.Paste")
			(net "M_H_CPU1_SB_DQ<12>")
		)
		(pad "119" smd rect
			(at -2.050034 42.0751 270)
			(size 0.519938 1.4986)
			(layers "F.Cu" "F.Mask" "F.Paste")
			(net "GND")
		)
		(pad "120" smd rect
			(at -2.050034 42.924984 270)
			(size 0.519938 1.4986)
			(layers "F.Cu" "F.Mask" "F.Paste")
			(net "M_H_CPU1_SB_DQ<13>")
		)
		(pad "121" smd rect
			(at -2.050034 43.775122 270)
			(size 0.519938 1.4986)
			(layers "F.Cu" "F.Mask" "F.Paste")
			(net "GND")
		)
		(pad "122" smd rect
			(at -2.050034 44.625006 270)
			(size 0.519938 1.4986)
			(layers "F.Cu" "F.Mask" "F.Paste")
			(net "M_H_CPU1_SB_DQ<16>")
		)
		(pad "123" smd rect
			(at -2.050034 45.47489 270)
			(size 0.519938 1.4986)
			(layers "F.Cu" "F.Mask" "F.Paste")
			(net "GND")
		)
		(pad "124" smd rect
			(at -2.050034 46.325028 270)
			(size 0.519938 1.4986)
			(layers "F.Cu" "F.Mask" "F.Paste")
			(net "M_H_CPU1_SB_DQ<17>")
		)
		(pad "125" smd rect
			(at -2.050034 47.174912 270)
			(size 0.519938 1.4986)
			(layers "F.Cu" "F.Mask" "F.Paste")
			(net "GND")
		)
		(pad "126" smd rect
			(at -2.050034 48.02505 270)
			(size 0.519938 1.4986)
			(layers "F.Cu" "F.Mask" "F.Paste")
			(net "M_H_CPU1_SB_DQS_DP<2>")
		)
		(pad "127" smd rect
			(at -2.050034 48.874934 270)
			(size 0.519938 1.4986)
			(layers "F.Cu" "F.Mask" "F.Paste")
			(net "M_H_CPU1_SB_DQS_DN<2>")
		)
		(pad "128" smd rect
			(at -2.050034 49.725072 270)
			(size 0.519938 1.4986)
			(layers "F.Cu" "F.Mask" "F.Paste")
			(net "GND")
		)
		(pad "129" smd rect
			(at -2.050034 50.574956 270)
			(size 0.519938 1.4986)
			(layers "F.Cu" "F.Mask" "F.Paste")
			(net "M_H_CPU1_SB_DQ<20>")
		)
		(pad "130" smd rect
			(at -2.050034 51.425094 270)
			(size 0.519938 1.4986)
			(layers "F.Cu" "F.Mask" "F.Paste")
			(net "GND")
		)
		(pad "131" smd rect
			(at -2.050034 52.274978 270)
			(size 0.519938 1.4986)
			(layers "F.Cu" "F.Mask" "F.Paste")
			(net "M_H_CPU1_SB_DQ<21>")
		)
		(pad "132" smd rect
			(at -2.050034 53.125116 270)
			(size 0.519938 1.4986)
			(layers "F.Cu" "F.Mask" "F.Paste")
			(net "GND")
		)
		(pad "133" smd rect
			(at -2.050034 53.975 270)
			(size 0.519938 1.4986)
			(layers "F.Cu" "F.Mask" "F.Paste")
			(net "M_H_CPU1_SB_DQ<24>")
		)
		(pad "134" smd rect
			(at -2.050034 54.824884 270)
			(size 0.519938 1.4986)
			(layers "F.Cu" "F.Mask" "F.Paste")
			(net "GND")
		)
		(pad "135" smd rect
			(at -2.050034 55.675022 270)
			(size 0.519938 1.4986)
			(layers "F.Cu" "F.Mask" "F.Paste")
			(net "M_H_CPU1_SB_DQ<25>")
		)
		(pad "136" smd rect
			(at -2.050034 56.524906 270)
			(size 0.519938 1.4986)
			(layers "F.Cu" "F.Mask" "F.Paste")
			(net "GND")
		)
		(pad "137" smd rect
			(at -2.050034 57.375044 270)
			(size 0.519938 1.4986)
			(layers "F.Cu" "F.Mask" "F.Paste")
			(net "M_H_CPU1_SB_DQS_DP<3>")
		)
	)
)
